(kicad_pcb
	(version 20260206)
	(generator "pcbnew")
	(generator_version "10.0")
	(general
		(thickness 1.6)
		(legacy_teardrops no)
	)
	(paper "A4")
	(title_block
		(title "01162023_DA0F0TEBIF0_F0T_Expander_BD_F_brd_V02_OCP.brd")
		(comment 1 "Grand Teton / footprint 1438 of 9728 (J13), pads 1-77 of 142")
	)
	(layers
		(0 "F.Cu" signal "TOP")
		(4 "In1.Cu" signal "GND")
		(6 "In2.Cu" signal "VCC")
		(8 "In3.Cu" signal "VCC1")
		(10 "In4.Cu" signal "GND1")
		(12 "In5.Cu" signal "IN1")
		(14 "In6.Cu" signal "GND2")
		(16 "In7.Cu" signal "IN2")
		(18 "In8.Cu" signal "GND3")
		(20 "In9.Cu" signal "IN3")
		(22 "In10.Cu" signal "GND4")
		(24 "In11.Cu" signal "IN4")
		(26 "In12.Cu" signal "GND5")
		(28 "In13.Cu" signal "IN5")
		(30 "In14.Cu" signal "GND6")
		(32 "In15.Cu" signal "IN6")
		(34 "In16.Cu" signal "GND7")
		(2 "B.Cu" signal "BOTTOM")
		(9 "F.Adhes" user "F.Adhesive")
		(11 "B.Adhes" user "B.Adhesive")
		(13 "F.Paste" user "Package Geometry/Pastemask Top")
		(15 "B.Paste" user "Package Geometry/Pastemask Bottom")
		(5 "F.SilkS" user "Ref Des/Silkscreen Top")
		(7 "B.SilkS" user "Ref Des/Silkscreen Bottom")
		(1 "F.Mask" user "Board Geometry/Soldermask Top")
		(3 "B.Mask" user "Board Geometry/Soldermask Bottom")
		(17 "Dwgs.User" user "User.Drawings")
		(19 "Cmts.User" user "User.Comments")
		(21 "Eco1.User" user "User.Eco1")
		(23 "Eco2.User" user "User.Eco2")
		(25 "Edge.Cuts" user "Board Geometry/Outline")
		(27 "Margin" user)
		(31 "F.CrtYd" user "Package Geometry/Place Bound Top")
		(29 "B.CrtYd" user "Package Geometry/Place Bound Bottom")
		(35 "F.Fab" user "Ref Des/Assembly Top")
		(33 "B.Fab" user "Ref Des/Assembly Bottom")
	)
	(footprint ""
		(layer "F.Cu")
		(at 331.490066 -412.090108)
		(property "Reference" "J13"
			(at -5.874512 6.282436 90)
			(unlocked yes)
			(layer "F.SilkS")
			(effects
				(font
					(size 2.032 1.524)
					(thickness 0.1524)
				)
				(justify left)
			)
		)
		(property "Value" ""
			(at 0 0 0)
			(layer "F.Fab")
			(effects
				(font
					(size 1.27 1.27)
				)
			)
		)
		(duplicate_pad_numbers_are_jumpers no)
		(pad "A1" thru_hole rect
			(at 0 0 180)
			(size 0.71628 0.71628)
			(drill 0.30988)
			(layers "*.Cu" "*.Mask")
			(remove_unused_layers no)
			(net "GPU_3V3IO_RSVD3_FFU_R")
			(clearance 0.0508)
			(thermal_gap 0.0508)
			(padstack
				(mode front_inner_back)
				(layer "Inner"
					(shape circle)
					(size 0.71628 0.71628)
					(clearance 0.0508)
				)
				(layer "B.Cu"
					(shape rect)
					(size 0.71628 0.71628)
					(clearance 0.0508)
				)
			)
		)
		(pad "A2" thru_hole circle
			(at 2.199894 0.199898 180)
			(size 0.906272 0.906272)
			(drill 0.499872)
			(layers "*.Cu" "*.Mask")
			(remove_unused_layers no)
			(net "GND")
			(clearance 0.0508)
			(thermal_gap 0.0508)
		)
		(pad "A3" thru_hole circle
			(at 4.400042 0 180)
			(size 0.71628 0.71628)
			(drill 0.30988)
			(layers "*.Cu" "*.Mask")
			(remove_unused_layers no)
			(net "PRSNT_GPU_A2_R_N")
			(clearance 0.0508)
			(thermal_gap 0.0508)
		)
		(pad "A4" thru_hole circle
			(at 6.599936 0.199898 180)
			(size 0.906272 0.906272)
			(drill 0.499872)
			(layers "*.Cu" "*.Mask")
			(remove_unused_layers no)
			(net "GND")
			(clearance 0.0508)
			(thermal_gap 0.0508)
		)
		(pad "A5" thru_hole circle
			(at 8.800084 0 180)
			(size 0.71628 0.71628)
			(drill 0.30988)
			(layers "*.Cu" "*.Mask")
			(remove_unused_layers no)
			(net "GPU_3V3IO_RSVD5_FFU_R")
			(clearance 0.0508)
			(thermal_gap 0.0508)
		)
		(pad "A6" thru_hole circle
			(at 10.999978 0.199898 180)
			(size 0.906272 0.906272)
			(drill 0.499872)
			(layers "*.Cu" "*.Mask")
			(remove_unused_layers no)
			(net "GND")
			(clearance 0.0508)
			(thermal_gap 0.0508)
		)
		(pad "A7" thru_hole circle
			(at 13.199872 0 180)
			(size 0.71628 0.71628)
			(drill 0.30988)
			(layers "*.Cu" "*.Mask")
			(remove_unused_layers no)
			(net "GPU_FPGA_OVERT_R_N")
			(clearance 0.0508)
			(thermal_gap 0.0508)
		)
		(pad "A8" thru_hole circle
			(at 15.40002 0.199898 180)
			(size 0.906272 0.906272)
			(drill 0.499872)
			(layers "*.Cu" "*.Mask")
			(remove_unused_layers no)
			(net "GND")
			(clearance 0.0508)
			(thermal_gap 0.0508)
		)
		(pad "A9" thru_hole circle
			(at 17.599914 0 180)
			(size 0.71628 0.71628)
			(drill 0.30988)
			(layers "*.Cu" "*.Mask")
			(remove_unused_layers no)
			(net "SWB_HSC_PWRGD")
			(clearance 0.0508)
			(thermal_gap 0.0508)
		)
		(pad "A10" thru_hole circle
			(at 19.800062 0.199898 180)
			(size 0.906272 0.906272)
			(drill 0.499872)
			(layers "*.Cu" "*.Mask")
			(remove_unused_layers no)
			(net "GND")
			(clearance 0.0508)
			(thermal_gap 0.0508)
		)
		(pad "B1" thru_hole circle
			(at 0 1.299972 180)
			(size 0.906272 0.906272)
			(drill 0.499872)
			(layers "*.Cu" "*.Mask")
			(remove_unused_layers no)
			(net "GND")
			(clearance 0.0508)
			(thermal_gap 0.0508)
		)
		(pad "B3" thru_hole circle
			(at 4.400042 1.299972 180)
			(size 0.906272 0.906272)
			(drill 0.499872)
			(layers "*.Cu" "*.Mask")
			(remove_unused_layers no)
			(net "GND")
			(clearance 0.0508)
			(thermal_gap 0.0508)
		)
		(pad "B5" thru_hole circle
			(at 8.800084 1.299972 180)
			(size 0.906272 0.906272)
			(drill 0.499872)
			(layers "*.Cu" "*.Mask")
			(remove_unused_layers no)
			(net "GND")
			(clearance 0.0508)
			(thermal_gap 0.0508)
		)
		(pad "B7" thru_hole circle
			(at 13.199872 1.299972 180)
			(size 0.906272 0.906272)
			(drill 0.499872)
			(layers "*.Cu" "*.Mask")
			(remove_unused_layers no)
			(net "GND")
			(clearance 0.0508)
			(thermal_gap 0.0508)
		)
		(pad "B9" thru_hole circle
			(at 17.599914 1.299972 180)
			(size 0.906272 0.906272)
			(drill 0.499872)
			(layers "*.Cu" "*.Mask")
			(remove_unused_layers no)
			(net "GND")
			(clearance 0.0508)
			(thermal_gap 0.0508)
		)
		(pad "B10" thru_hole circle
			(at 19.800062 1.500124 180)
			(size 0.71628 0.71628)
			(drill 0.30988)
			(layers "*.Cu" "*.Mask")
			(remove_unused_layers no)
			(net "Net_8904")
			(clearance 0.0508)
			(thermal_gap 0.0508)
		)
		(pad "C9" thru_hole circle
			(at 17.599914 2.599944 180)
			(size 0.71628 0.71628)
			(drill 0.30988)
			(layers "*.Cu" "*.Mask")
			(remove_unused_layers no)
			(net "Net_8902")
			(clearance 0.0508)
			(thermal_gap 0.0508)
		)
		(pad "C10" thru_hole circle
			(at 19.800062 2.800096 180)
			(size 0.71628 0.71628)
			(drill 0.30988)
			(layers "*.Cu" "*.Mask")
			(remove_unused_layers no)
			(net "Net_8903")
			(clearance 0.0508)
			(thermal_gap 0.0508)
		)
		(pad "D2" thru_hole circle
			(at 2.199894 4.100068 180)
			(size 0.906272 0.906272)
			(drill 0.499872)
			(layers "*.Cu" "*.Mask")
			(remove_unused_layers no)
			(net "GND")
			(clearance 0.0508)
			(thermal_gap 0.0508)
		)
		(pad "D4" thru_hole circle
			(at 6.599936 4.100068 180)
			(size 0.906272 0.906272)
			(drill 0.499872)
			(layers "*.Cu" "*.Mask")
			(remove_unused_layers no)
			(net "GND")
			(clearance 0.0508)
			(thermal_gap 0.0508)
		)
		(pad "D6" thru_hole circle
			(at 10.999978 4.100068 180)
			(size 0.906272 0.906272)
			(drill 0.499872)
			(layers "*.Cu" "*.Mask")
			(remove_unused_layers no)
			(net "GND")
			(clearance 0.0508)
			(thermal_gap 0.0508)
		)
		(pad "D8" thru_hole circle
			(at 15.40002 4.100068 180)
			(size 0.906272 0.906272)
			(drill 0.499872)
			(layers "*.Cu" "*.Mask")
			(remove_unused_layers no)
			(net "GND")
			(clearance 0.0508)
			(thermal_gap 0.0508)
		)
		(pad "D9" thru_hole circle
			(at 17.599914 3.899916 180)
			(size 0.71628 0.71628)
			(drill 0.30988)
			(layers "*.Cu" "*.Mask")
			(remove_unused_layers no)
			(net "Net_8901")
			(clearance 0.0508)
			(thermal_gap 0.0508)
		)
		(pad "D10" thru_hole circle
			(at 19.800062 4.100068 180)
			(size 0.906272 0.906272)
			(drill 0.499872)
			(layers "*.Cu" "*.Mask")
			(remove_unused_layers no)
			(net "GND")
			(clearance 0.0508)
			(thermal_gap 0.0508)
		)
		(pad "E1" thru_hole circle
			(at 0 5.199888 180)
			(size 0.906272 0.906272)
			(drill 0.499872)
			(layers "*.Cu" "*.Mask")
			(remove_unused_layers no)
			(net "GND")
			(clearance 0.0508)
			(thermal_gap 0.0508)
		)
		(pad "E3" thru_hole circle
			(at 4.400042 5.199888 180)
			(size 0.906272 0.906272)
			(drill 0.499872)
			(layers "*.Cu" "*.Mask")
			(remove_unused_layers no)
			(net "GND")
			(clearance 0.0508)
			(thermal_gap 0.0508)
		)
		(pad "E5" thru_hole circle
			(at 8.800084 5.199888 180)
			(size 0.906272 0.906272)
			(drill 0.499872)
			(layers "*.Cu" "*.Mask")
			(remove_unused_layers no)
			(net "GND")
			(clearance 0.0508)
			(thermal_gap 0.0508)
		)
		(pad "E7" thru_hole circle
			(at 13.199872 5.199888 180)
			(size 0.906272 0.906272)
			(drill 0.499872)
			(layers "*.Cu" "*.Mask")
			(remove_unused_layers no)
			(net "GND")
			(clearance 0.0508)
			(thermal_gap 0.0508)
		)
		(pad "E9" thru_hole circle
			(at 17.599914 5.199888 180)
			(size 0.906272 0.906272)
			(drill 0.499872)
			(layers "*.Cu" "*.Mask")
			(remove_unused_layers no)
			(net "GND")
			(clearance 0.0508)
			(thermal_gap 0.0508)
		)
		(pad "E10" thru_hole circle
			(at 19.800062 5.40004 180)
			(size 0.71628 0.71628)
			(drill 0.30988)
			(layers "*.Cu" "*.Mask")
			(remove_unused_layers no)
			(net "Net_8900")
			(clearance 0.0508)
			(thermal_gap 0.0508)
		)
		(pad "F9" thru_hole circle
			(at 17.599914 6.500114 180)
			(size 0.71628 0.71628)
			(drill 0.30988)
			(layers "*.Cu" "*.Mask")
			(remove_unused_layers no)
			(net "Net_8898")
			(clearance 0.0508)
			(thermal_gap 0.0508)
		)
		(pad "F10" thru_hole circle
			(at 19.800062 6.700012 180)
			(size 0.71628 0.71628)
			(drill 0.30988)
			(layers "*.Cu" "*.Mask")
			(remove_unused_layers no)
			(net "Net_8899")
			(clearance 0.0508)
			(thermal_gap 0.0508)
		)
		(pad "G2" thru_hole circle
			(at 2.199894 7.999984 180)
			(size 0.906272 0.906272)
			(drill 0.499872)
			(layers "*.Cu" "*.Mask")
			(remove_unused_layers no)
			(net "GND")
			(clearance 0.0508)
			(thermal_gap 0.0508)
		)
		(pad "G4" thru_hole circle
			(at 6.599936 7.999984 180)
			(size 0.906272 0.906272)
			(drill 0.499872)
			(layers "*.Cu" "*.Mask")
			(remove_unused_layers no)
			(net "GND")
			(clearance 0.0508)
			(thermal_gap 0.0508)
		)
		(pad "G6" thru_hole circle
			(at 10.999978 7.999984 180)
			(size 0.906272 0.906272)
			(drill 0.499872)
			(layers "*.Cu" "*.Mask")
			(remove_unused_layers no)
			(net "GND")
			(clearance 0.0508)
			(thermal_gap 0.0508)
		)
		(pad "G8" thru_hole circle
			(at 15.40002 7.999984 180)
			(size 0.906272 0.906272)
			(drill 0.499872)
			(layers "*.Cu" "*.Mask")
			(remove_unused_layers no)
			(net "GND")
			(clearance 0.0508)
			(thermal_gap 0.0508)
		)
		(pad "G9" thru_hole circle
			(at 17.599914 7.800086 180)
			(size 0.71628 0.71628)
			(drill 0.30988)
			(layers "*.Cu" "*.Mask")
			(remove_unused_layers no)
			(net "Net_8897")
			(clearance 0.0508)
			(thermal_gap 0.0508)
		)
		(pad "G10" thru_hole circle
			(at 19.800062 7.999984 180)
			(size 0.906272 0.906272)
			(drill 0.499872)
			(layers "*.Cu" "*.Mask")
			(remove_unused_layers no)
			(net "GND")
			(clearance 0.0508)
			(thermal_gap 0.0508)
		)
		(pad "H1" thru_hole circle
			(at 0 9.100058 180)
			(size 0.906272 0.906272)
			(drill 0.499872)
			(layers "*.Cu" "*.Mask")
			(remove_unused_layers no)
			(net "GND")
			(clearance 0.0508)
			(thermal_gap 0.0508)
		)
		(pad "H3" thru_hole circle
			(at 4.400042 9.100058 180)
			(size 0.906272 0.906272)
			(drill 0.499872)
			(layers "*.Cu" "*.Mask")
			(remove_unused_layers no)
			(net "GND")
			(clearance 0.0508)
			(thermal_gap 0.0508)
		)
		(pad "H5" thru_hole circle
			(at 8.800084 9.100058 180)
			(size 0.906272 0.906272)
			(drill 0.499872)
			(layers "*.Cu" "*.Mask")
			(remove_unused_layers no)
			(net "GND")
			(clearance 0.0508)
			(thermal_gap 0.0508)
		)
		(pad "H7" thru_hole circle
			(at 13.199872 9.100058 180)
			(size 0.906272 0.906272)
			(drill 0.499872)
			(layers "*.Cu" "*.Mask")
			(remove_unused_layers no)
			(net "GND")
			(clearance 0.0508)
			(thermal_gap 0.0508)
		)
		(pad "H9" thru_hole circle
			(at 17.599914 9.100058 180)
			(size 0.906272 0.906272)
			(drill 0.499872)
			(layers "*.Cu" "*.Mask")
			(remove_unused_layers no)
			(net "GND")
			(clearance 0.0508)
			(thermal_gap 0.0508)
		)
		(pad "H10" thru_hole circle
			(at 19.800062 9.299956 180)
			(size 0.71628 0.71628)
			(drill 0.30988)
			(layers "*.Cu" "*.Mask")
			(remove_unused_layers no)
			(net "Net_8896")
			(clearance 0.0508)
			(thermal_gap 0.0508)
		)
		(pad "I9" thru_hole circle
			(at 17.599914 10.40003 180)
			(size 0.71628 0.71628)
			(drill 0.30988)
			(layers "*.Cu" "*.Mask")
			(remove_unused_layers no)
			(net "Net_8894")
			(clearance 0.0508)
			(thermal_gap 0.0508)
		)
		(pad "I10" thru_hole circle
			(at 19.800062 10.599928 180)
			(size 0.71628 0.71628)
			(drill 0.30988)
			(layers "*.Cu" "*.Mask")
			(remove_unused_layers no)
			(net "Net_8895")
			(clearance 0.0508)
			(thermal_gap 0.0508)
		)
		(pad "J2" thru_hole circle
			(at 2.199894 11.8999 180)
			(size 0.906272 0.906272)
			(drill 0.499872)
			(layers "*.Cu" "*.Mask")
			(remove_unused_layers no)
			(net "GND")
			(clearance 0.0508)
			(thermal_gap 0.0508)
		)
		(pad "J4" thru_hole circle
			(at 6.599936 11.8999 180)
			(size 0.906272 0.906272)
			(drill 0.499872)
			(layers "*.Cu" "*.Mask")
			(remove_unused_layers no)
			(net "GND")
			(clearance 0.0508)
			(thermal_gap 0.0508)
		)
		(pad "J6" thru_hole circle
			(at 10.999978 11.8999 180)
			(size 0.906272 0.906272)
			(drill 0.499872)
			(layers "*.Cu" "*.Mask")
			(remove_unused_layers no)
			(net "GND")
			(clearance 0.0508)
			(thermal_gap 0.0508)
		)
		(pad "J8" thru_hole circle
			(at 15.40002 11.8999 180)
			(size 0.906272 0.906272)
			(drill 0.499872)
			(layers "*.Cu" "*.Mask")
			(remove_unused_layers no)
			(net "GND")
			(clearance 0.0508)
			(thermal_gap 0.0508)
		)
		(pad "J9" thru_hole circle
			(at 17.599914 11.700002 180)
			(size 0.71628 0.71628)
			(drill 0.30988)
			(layers "*.Cu" "*.Mask")
			(remove_unused_layers no)
			(net "Net_8893")
			(clearance 0.0508)
			(thermal_gap 0.0508)
		)
		(pad "J10" thru_hole circle
			(at 19.800062 11.8999 180)
			(size 0.906272 0.906272)
			(drill 0.499872)
			(layers "*.Cu" "*.Mask")
			(remove_unused_layers no)
			(net "GND")
			(clearance 0.0508)
			(thermal_gap 0.0508)
		)
		(pad "K1" thru_hole circle
			(at 0 12.999974 180)
			(size 0.906272 0.906272)
			(drill 0.499872)
			(layers "*.Cu" "*.Mask")
			(remove_unused_layers no)
			(net "GND")
			(clearance 0.0508)
			(thermal_gap 0.0508)
		)
		(pad "K3" thru_hole circle
			(at 4.400042 12.999974 180)
			(size 0.906272 0.906272)
			(drill 0.499872)
			(layers "*.Cu" "*.Mask")
			(remove_unused_layers no)
			(net "GND")
			(clearance 0.0508)
			(thermal_gap 0.0508)
		)
		(pad "K5" thru_hole circle
			(at 8.800084 12.999974 180)
			(size 0.906272 0.906272)
			(drill 0.499872)
			(layers "*.Cu" "*.Mask")
			(remove_unused_layers no)
			(net "GND")
			(clearance 0.0508)
			(thermal_gap 0.0508)
		)
		(pad "K7" thru_hole circle
			(at 13.199872 12.999974 180)
			(size 0.906272 0.906272)
			(drill 0.499872)
			(layers "*.Cu" "*.Mask")
			(remove_unused_layers no)
			(net "GND")
			(clearance 0.0508)
			(thermal_gap 0.0508)
		)
		(pad "K9" thru_hole circle
			(at 17.599914 12.999974 180)
			(size 0.906272 0.906272)
			(drill 0.499872)
			(layers "*.Cu" "*.Mask")
			(remove_unused_layers no)
			(net "GND")
			(clearance 0.0508)
			(thermal_gap 0.0508)
		)
		(pad "K10" thru_hole circle
			(at 19.800062 13.199872 180)
			(size 0.71628 0.71628)
			(drill 0.30988)
			(layers "*.Cu" "*.Mask")
			(remove_unused_layers no)
			(net "Net_8892")
			(clearance 0.0508)
			(thermal_gap 0.0508)
		)
		(pad "L9" thru_hole circle
			(at 17.599914 14.299946 180)
			(size 0.71628 0.71628)
			(drill 0.30988)
			(layers "*.Cu" "*.Mask")
			(remove_unused_layers no)
			(net "Net_8890")
			(clearance 0.0508)
			(thermal_gap 0.0508)
		)
		(pad "L10" thru_hole circle
			(at 19.800062 14.500098 180)
			(size 0.71628 0.71628)
			(drill 0.30988)
			(layers "*.Cu" "*.Mask")
			(remove_unused_layers no)
			(net "Net_8891")
			(clearance 0.0508)
			(thermal_gap 0.0508)
		)
		(pad "M1_2" thru_hole circle
			(at 2.199894 15.80007 180)
			(size 0.906272 0.906272)
			(drill 0.499872)
			(layers "*.Cu" "*.Mask")
			(remove_unused_layers no)
			(net "GND")
			(clearance 0.0508)
			(thermal_gap 0.0508)
		)
		(pad "M1_4" thru_hole circle
			(at 6.599936 15.80007 180)
			(size 0.906272 0.906272)
			(drill 0.499872)
			(layers "*.Cu" "*.Mask")
			(remove_unused_layers no)
			(net "GND")
			(clearance 0.0508)
			(thermal_gap 0.0508)
		)
		(pad "M1_6" thru_hole circle
			(at 10.999978 15.80007 180)
			(size 0.906272 0.906272)
			(drill 0.499872)
			(layers "*.Cu" "*.Mask")
			(remove_unused_layers no)
			(net "GND")
			(clearance 0.0508)
			(thermal_gap 0.0508)
		)
		(pad "M1_8" thru_hole circle
			(at 15.40002 15.80007 180)
			(size 0.906272 0.906272)
			(drill 0.499872)
			(layers "*.Cu" "*.Mask")
			(remove_unused_layers no)
			(net "GND")
			(clearance 0.0508)
			(thermal_gap 0.0508)
		)
		(pad "M1_10" thru_hole circle
			(at 19.800062 15.80007 180)
			(size 0.906272 0.906272)
			(drill 0.499872)
			(layers "*.Cu" "*.Mask")
			(remove_unused_layers no)
			(net "GND")
			(clearance 0.0508)
			(thermal_gap 0.0508)
		)
		(pad "M2_2" thru_hole circle
			(at 2.199894 26.2001 180)
			(size 0.906272 0.906272)
			(drill 0.499872)
			(layers "*.Cu" "*.Mask")
			(remove_unused_layers no)
			(net "GND")
			(clearance 0.0508)
			(thermal_gap 0.0508)
		)
		(pad "M2_4" thru_hole circle
			(at 6.599936 26.2001 180)
			(size 0.906272 0.906272)
			(drill 0.499872)
			(layers "*.Cu" "*.Mask")
			(remove_unused_layers no)
			(net "GND")
			(clearance 0.0508)
			(thermal_gap 0.0508)
		)
		(pad "M2_6" thru_hole circle
			(at 10.999978 26.2001 180)
			(size 0.906272 0.906272)
			(drill 0.499872)
			(layers "*.Cu" "*.Mask")
			(remove_unused_layers no)
			(net "GND")
			(clearance 0.0508)
			(thermal_gap 0.0508)
		)
		(pad "M2_8" thru_hole circle
			(at 15.40002 26.2001 180)
			(size 0.906272 0.906272)
			(drill 0.499872)
			(layers "*.Cu" "*.Mask")
			(remove_unused_layers no)
			(net "GND")
			(clearance 0.0508)
			(thermal_gap 0.0508)
		)
		(pad "M2_10" thru_hole circle
			(at 19.800062 26.2001 180)
			(size 0.906272 0.906272)
			(drill 0.499872)
			(layers "*.Cu" "*.Mask")
			(remove_unused_layers no)
			(net "GND")
			(clearance 0.0508)
			(thermal_gap 0.0508)
		)
		(pad "M9" thru_hole circle
			(at 17.599914 15.599918 180)
			(size 0.71628 0.71628)
			(drill 0.30988)
			(layers "*.Cu" "*.Mask")
			(remove_unused_layers no)
			(net "Net_8889")
			(clearance 0.0508)
			(thermal_gap 0.0508)
		)
		(pad "N1_1" thru_hole circle
			(at 0 16.89989 180)
			(size 0.906272 0.906272)
			(drill 0.499872)
			(layers "*.Cu" "*.Mask")
			(remove_unused_layers no)
			(net "GND")
			(clearance 0.0508)
			(thermal_gap 0.0508)
		)
		(pad "N1_3" thru_hole circle
			(at 4.400042 16.89989 180)
			(size 0.906272 0.906272)
			(drill 0.499872)
			(layers "*.Cu" "*.Mask")
			(remove_unused_layers no)
			(net "GND")
			(clearance 0.0508)
			(thermal_gap 0.0508)
		)
		(pad "N1_5" thru_hole circle
			(at 8.800084 16.89989 180)
			(size 0.906272 0.906272)
			(drill 0.499872)
			(layers "*.Cu" "*.Mask")
			(remove_unused_layers no)
			(net "GND")
			(clearance 0.0508)
			(thermal_gap 0.0508)
		)
		(pad "N1_7" thru_hole circle
			(at 13.199872 16.89989 180)
			(size 0.906272 0.906272)
			(drill 0.499872)
			(layers "*.Cu" "*.Mask")
			(remove_unused_layers no)
			(net "GND")
			(clearance 0.0508)
			(thermal_gap 0.0508)
		)
		(pad "N1_9" thru_hole circle
			(at 17.599914 16.89989 180)
			(size 0.906272 0.906272)
			(drill 0.499872)
			(layers "*.Cu" "*.Mask")
			(remove_unused_layers no)
			(net "GND")
			(clearance 0.0508)
			(thermal_gap 0.0508)
		)
		(pad "N2_1" thru_hole circle
			(at 0 27.29992 180)
			(size 0.906272 0.906272)
			(drill 0.499872)
			(layers "*.Cu" "*.Mask")
			(remove_unused_layers no)
			(net "GND")
			(clearance 0.0508)
			(thermal_gap 0.0508)
		)
	)
)
